# BASEBOARD_FAB2 (Tioga Pass) — schematic netlist excerpt (pin names and nets, part order shuffled) for the footprints in the layout excerpt that follows; sources: Cadence DE-HDL packaged netlist, KiCad conversion of Wiwynn_Tioga_Pass_MB.brd

C9L5  CAP  10UF 16V 10% X6S  pkg 0805  page 227 : A = VR_FET_SW_P12V_STBY_PVDDQ_KLM ; B = GND
C2U23  CAP_A  0.1UF 16V 10% X7R  pkg 0402V  page 108 : A = P3V3_STBY ; B = GND
R1M12  RES  10.0K 1% CHIP  pkg 0402  page 177 : A = P3V3 ; B = LED_SAS_ACT_R_N

(kicad_pcb
	(version 20260206)
	(generator "pcbnew")
	(generator_version "10.0")
	(general
		(thickness 1.6)
		(legacy_teardrops no)
	)
	(paper "A4")
	(title_block
		(title "Wiwynn_Tioga_Pass_MB.brd")
		(comment 1 "Tioga Pass / footprints 4739-4741 of 4770")
	)
	(layers
		(0 "F.Cu" signal "TOP")
		(4 "In1.Cu" signal "L2GND")
		(6 "In2.Cu" signal "L3")
		(8 "In3.Cu" signal "L4GND")
		(10 "In4.Cu" signal "L5")
		(12 "In5.Cu" signal "L6GND")
		(14 "In6.Cu" signal "L7VCC")
		(16 "In7.Cu" signal "L8VCC")
		(18 "In8.Cu" signal "L9GND")
		(20 "In9.Cu" signal "L10")
		(22 "In10.Cu" signal "L11GND")
		(24 "In11.Cu" signal "L12")
		(26 "In12.Cu" signal "L13GND")
		(2 "B.Cu" signal "BOTTOM")
		(9 "F.Adhes" user "F.Adhesive")
		(11 "B.Adhes" user "B.Adhesive")
		(13 "F.Paste" user "Package Geometry/Pastemask Top")
		(15 "B.Paste" user "Package Geometry/Pastemask Bottom")
		(5 "F.SilkS" user "Ref Des/Silkscreen Top")
		(7 "B.SilkS" user "Ref Des/Silkscreen Bottom")
		(1 "F.Mask" user "Board Geometry/Soldermask Top")
		(3 "B.Mask" user "Board Geometry/Soldermask Bottom")
		(17 "Dwgs.User" user "User.Drawings")
		(19 "Cmts.User" user "User.Comments")
		(21 "Eco1.User" user "User.Eco1")
		(23 "Eco2.User" user "User.Eco2")
		(25 "Edge.Cuts" user "Board Geometry/Outline")
		(27 "Margin" user)
		(31 "F.CrtYd" user "Package Geometry/Place Bound Top")
		(29 "B.CrtYd" user "Package Geometry/Place Bound Bottom")
		(35 "F.Fab" user "Ref Des/Assembly Top")
		(33 "B.Fab" user "Ref Des/Assembly Bottom")
	)
	(footprint ""
		(layer "B.Cu")
		(at 494.3729 -124.0663 180)
		(property "Reference" "R1M12"
			(at 0 0 0)
			(layer "B.SilkS")
			(hide yes)
			(effects
				(font
					(size 1.27 1.27)
				)
				(justify mirror)
			)
		)
		(property "Value" ""
			(at 0 0 0)
			(layer "B.Fab")
			(effects
				(font
					(size 1.27 1.27)
				)
				(justify mirror)
			)
		)
		(duplicate_pad_numbers_are_jumpers no)
		(fp_poly
			(pts
				(xy 0.2794 -0.1016) (xy -0.2794 -0.1016) (xy -0.2794 0.9906) (xy 0.2794 0.9906)
			)
			(stroke
				(width 0)
				(type default)
			)
			(fill no)
			(layer "B.CrtYd")
		)
		(fp_line
			(start 0.2794 0.9906)
			(end -0.2794 0.9906)
			(stroke
				(width 0.1)
				(type default)
			)
			(layer "B.Fab")
		)
		(fp_line
			(start 0.2794 -0.1016)
			(end 0.2794 0.9906)
			(stroke
				(width 0.1)
				(type default)
			)
			(layer "B.Fab")
		)
		(fp_line
			(start -0.2794 0.9906)
			(end -0.2794 -0.1016)
			(stroke
				(width 0.1)
				(type default)
			)
			(layer "B.Fab")
		)
		(fp_line
			(start -0.2794 -0.1016)
			(end 0.2794 -0.1016)
			(stroke
				(width 0.1)
				(type default)
			)
			(layer "B.Fab")
		)
		(pad "1" smd rect
			(at 0 0)
			(size 0.508 0.508)
			(layers "B.Cu" "B.Mask" "B.Paste")
			(net "P3V3")
		)
		(pad "2" smd rect
			(at 0 0.889)
			(size 0.508 0.508)
			(layers "B.Cu" "B.Mask" "B.Paste")
			(net "LED_SAS_ACT_R_N")
		)
		(zone
			(layer "B.Cu")
			(hatch none 0.5)
			(connect_pads
				(clearance 0)
			)
			(min_thickness 0.25)
			(keepout
				(tracks not_allowed)
				(vias allowed)
				(pads allowed)
				(copperpour not_allowed)
				(footprints allowed)
			)
			(placement
				(enabled no)
				(sheetname "")
			)
			(fill
				(thermal_gap 0.5)
				(thermal_bridge_width 0.5)
				(island_removal_mode 0)
			)
			(polygon
				(pts
					(xy 494.1189 -124.7013) (xy 494.6269 -124.7013) (xy 494.6269 -124.3203) (xy 494.1189 -124.3203)
				)
			)
		)
		(zone
			(layer "B.Cu")
			(hatch none 0.5)
			(connect_pads
				(clearance 0)
			)
			(min_thickness 0.25)
			(keepout
				(tracks allowed)
				(vias not_allowed)
				(pads allowed)
				(copperpour not_allowed)
				(footprints allowed)
			)
			(placement
				(enabled no)
				(sheetname "")
			)
			(fill
				(thermal_gap 0.5)
				(thermal_bridge_width 0.5)
				(island_removal_mode 0)
			)
			(polygon
				(pts
					(xy 494.1189 -124.3203) (xy 494.6269 -124.3203) (xy 494.6269 -124.7013) (xy 494.1189 -124.7013)
				)
			)
		)
	)
	(footprint ""
		(layer "B.Cu")
		(at 463.677 -4.5085)
		(property "Reference" "C2U23"
			(at 0 0 0)
			(layer "B.SilkS")
			(hide yes)
			(effects
				(font
					(size 1.27 1.27)
				)
				(justify mirror)
			)
		)
		(property "Value" ""
			(at 0 0 0)
			(layer "B.Fab")
			(effects
				(font
					(size 1.27 1.27)
				)
				(justify mirror)
			)
		)
		(duplicate_pad_numbers_are_jumpers no)
		(fp_poly
			(pts
				(xy -0.3048 -0.1016) (xy -0.3048 0.9906) (xy 0.3048 0.9906) (xy 0.3048 -0.1016)
			)
			(stroke
				(width 0)
				(type default)
			)
			(fill no)
			(layer "B.CrtYd")
		)
		(fp_line
			(start -0.3048 -0.1016)
			(end 0.3048 -0.1016)
			(stroke
				(width 0.1)
				(type default)
			)
			(layer "B.Fab")
		)
		(fp_line
			(start -0.3048 0.9906)
			(end -0.3048 -0.1016)
			(stroke
				(width 0.1)
				(type default)
			)
			(layer "B.Fab")
		)
		(fp_line
			(start 0.3048 -0.1016)
			(end 0.3048 0.9906)
			(stroke
				(width 0.1)
				(type default)
			)
			(layer "B.Fab")
		)
		(fp_line
			(start 0.3048 0.9906)
			(end -0.3048 0.9906)
			(stroke
				(width 0.1)
				(type default)
			)
			(layer "B.Fab")
		)
		(pad "1" smd rect
			(at 0 0 180)
			(size 0.508 0.508)
			(layers "B.Cu" "B.Mask" "B.Paste")
			(net "P3V3_STBY")
		)
		(pad "2" smd rect
			(at 0 0.889 180)
			(size 0.508 0.508)
			(layers "B.Cu" "B.Mask" "B.Paste")
			(net "GND")
		)
		(zone
			(layer "B.Cu")
			(hatch none 0.5)
			(connect_pads
				(clearance 0)
			)
			(min_thickness 0.25)
			(keepout
				(tracks allowed)
				(vias not_allowed)
				(pads allowed)
				(copperpour not_allowed)
				(footprints allowed)
			)
			(placement
				(enabled no)
				(sheetname "")
			)
			(fill
				(thermal_gap 0.5)
				(thermal_bridge_width 0.5)
				(island_removal_mode 0)
			)
			(polygon
				(pts
					(xy 463.931 -4.2545) (xy 463.423 -4.2545) (xy 463.423 -3.8735) (xy 463.931 -3.8735)
				)
			)
		)
		(zone
			(layer "B.Cu")
			(hatch none 0.5)
			(connect_pads
				(clearance 0)
			)
			(min_thickness 0.25)
			(keepout
				(tracks not_allowed)
				(vias allowed)
				(pads allowed)
				(copperpour not_allowed)
				(footprints allowed)
			)
			(placement
				(enabled no)
				(sheetname "")
			)
			(fill
				(thermal_gap 0.5)
				(thermal_bridge_width 0.5)
				(island_removal_mode 0)
			)
			(polygon
				(pts
					(xy 463.931 -3.8735) (xy 463.423 -3.8735) (xy 463.423 -4.2545) (xy 463.931 -4.2545)
				)
			)
		)
	)
	(footprint ""
		(layer "B.Cu")
		(at 1.3462 -149.987 90)
		(property "Reference" "C9L5"
			(at 0 0 90)
			(layer "B.SilkS")
			(hide yes)
			(effects
				(font
					(size 1.27 1.27)
				)
				(justify mirror)
			)
		)
		(property "Value" ""
			(at 0 0 90)
			(layer "B.Fab")
			(effects
				(font
					(size 1.27 1.27)
				)
				(justify mirror)
			)
		)
		(duplicate_pad_numbers_are_jumpers no)
		(fp_rect
			(start -0.7239 -0.2159)
			(end 0.7239 1.9939)
			(stroke
				(width 0)
				(type default)
			)
			(fill no)
			(layer "B.CrtYd")
		)
		(fp_line
			(start 0.7239 -0.2159)
			(end 0.7239 1.9939)
			(stroke
				(width 0.1)
				(type default)
			)
			(layer "B.Fab")
		)
		(fp_line
			(start -0.7239 -0.2159)
			(end 0.7239 -0.2159)
			(stroke
				(width 0.1)
				(type default)
			)
			(layer "B.Fab")
		)
		(fp_line
			(start 0.7239 1.9939)
			(end -0.7239 1.9939)
			(stroke
				(width 0.1)
				(type default)
			)
			(layer "B.Fab")
		)
		(fp_line
			(start -0.7239 1.9939)
			(end -0.7239 -0.2159)
			(stroke
				(width 0.1)
				(type default)
			)
			(layer "B.Fab")
		)
		(pad "1" smd rect
			(at 0 0 270)
			(size 1.27 1.016)
			(layers "B.Cu" "B.Mask" "B.Paste")
			(net "VR_FET_SW_P12V_STBY_PVDDQ_KLM")
		)
		(pad "2" smd rect
			(at 0 1.778 270)
			(size 1.27 1.016)
			(layers "B.Cu" "B.Mask" "B.Paste")
			(net "GND")
		)
		(zone
			(layer "B.Cu")
			(hatch none 0.5)
			(connect_pads
				(clearance 0)
			)
			(min_thickness 0.25)
			(keepout
				(tracks not_allowed)
				(vias allowed)
				(pads allowed)
				(copperpour not_allowed)
				(footprints allowed)
			)
			(placement
				(enabled no)
				(sheetname "")
			)
			(fill
				(thermal_gap 0.5)
				(thermal_bridge_width 0.5)
				(island_removal_mode 0)
			)
			(polygon
				(pts
					(xy 1.8542 -149.352) (xy 2.6162 -149.352) (xy 2.6162 -150.622) (xy 1.8542 -150.622)
				)
			)
		)
	)
)
